(kicad_pcb
	(version 20241229)
	(generator "pcbnew")
	(generator_version "9.0")
	(general
		(thickness 1.6)
		(legacy_teardrops no)
	)
	(paper "A4")
	(title_block
		(title "environment-sensor")
		(comment 1 "footprints 12-17 of 109")
	)
	(layers
		(0 "F.Cu" signal)
		(4 "In1.Cu" signal)
		(6 "In2.Cu" signal)
		(2 "B.Cu" signal)
		(9 "F.Adhes" user "F.Adhesive")
		(11 "B.Adhes" user "B.Adhesive")
		(13 "F.Paste" user)
		(15 "B.Paste" user)
		(5 "F.SilkS" user "F.Silkscreen")
		(7 "B.SilkS" user "B.Silkscreen")
		(1 "F.Mask" user)
		(3 "B.Mask" user)
		(17 "Dwgs.User" user "User.Drawings")
		(19 "Cmts.User" user "User.Comments")
		(21 "Eco1.User" user "User.Eco1")
		(23 "Eco2.User" user "User.Eco2")
		(25 "Edge.Cuts" user)
		(27 "Margin" user)
		(31 "F.CrtYd" user "F.Courtyard")
		(29 "B.CrtYd" user "B.Courtyard")
		(35 "F.Fab" user)
		(33 "B.Fab" user)
	)
	(footprint "antmicro-footprints:R_0402_1005Metric"
		(layer "F.Cu")
		(at 198.5 133.6 180)
		(descr "Resistor SMD 0402")
		(tags "resistor SMD 0402")
		(property "Reference" "R38"
			(at -0.85 -0.4 180)
			(layer "F.SilkS")
			(effects
				(font
					(size 0.7 0.7)
					(thickness 0.15)
				)
				(justify left bottom)
			)
		)
		(property "Value" "R_5k1_0402"
			(at 0 1.4 180)
			(layer "F.Fab")
			(effects
				(font
					(size 0.7 0.7)
					(thickness 0.15)
				)
				(justify left bottom)
			)
		)
		(property "Description" "SMD Chip Resistor, 5.1 kohm, ± 1%, 63 mW, 0402 [1005 Metric], Thick Film, General Purpose"
			(at 0 0 180)
			(layer "F.Fab")
			(hide yes)
			(effects
				(font
					(size 1.27 1.27)
					(thickness 0.15)
				)
			)
		)
		(property "Author" "Antmicro"
			(at 397 267.2 0)
			(layer "F.Fab")
			(hide yes)
			(effects
				(font
					(size 1 1)
					(thickness 0.15)
				)
			)
		)
		(property "License" "Apache-2.0"
			(at 397 267.2 0)
			(layer "F.Fab")
			(hide yes)
			(effects
				(font
					(size 1 1)
					(thickness 0.15)
				)
			)
		)
		(property "MPN" "CR0402-FX-5101GLF"
			(at 397 267.2 0)
			(layer "F.Fab")
			(hide yes)
			(effects
				(font
					(size 1 1)
					(thickness 0.15)
				)
			)
		)
		(property "Manufacturer" "Bourns"
			(at 397 267.2 0)
			(layer "F.Fab")
			(hide yes)
			(effects
				(font
					(size 1 1)
					(thickness 0.15)
				)
			)
		)
		(property "Public" "False"
			(at 397 267.2 0)
			(layer "F.Fab")
			(hide yes)
			(effects
				(font
					(size 1 1)
					(thickness 0.15)
				)
			)
		)
		(property "Tolerance" "1%"
			(at 397 267.2 0)
			(layer "F.Fab")
			(hide yes)
			(effects
				(font
					(size 1 1)
					(thickness 0.15)
				)
			)
		)
		(property "Val" "5k1"
			(at 397 267.2 0)
			(layer "F.Fab")
			(hide yes)
			(effects
				(font
					(size 1 1)
					(thickness 0.15)
				)
			)
		)
		(sheetfile "environment-sensor.kicad_sch")
		(attr smd)
		(fp_rect
			(start -0.925 -0.47)
			(end 0.925 0.47)
			(stroke
				(width 0.05)
				(type default)
			)
			(fill no)
			(layer "F.CrtYd")
		)
		(fp_rect
			(start -0.5 -0.25)
			(end 0.5 0.25)
			(stroke
				(width 0.15)
				(type solid)
			)
			(fill no)
			(layer "F.Fab")
		)
		(pad "1" smd roundrect
			(at -0.48 0 180)
			(size 0.59 0.64)
			(layers "F.Cu" "F.Mask" "F.Paste")
			(roundrect_rratio 0.25)
			(net 9 "I2C_1_SDA")
			(pintype "passive")
		)
		(pad "2" smd roundrect
			(at 0.48 0 180)
			(size 0.59 0.64)
			(layers "F.Cu" "F.Mask" "F.Paste")
			(roundrect_rratio 0.25)
			(net 2 "+3V3")
			(pintype "passive")
		)
	)
	(footprint "antmicro-footprints:C_0402_1005Metric"
		(layer "F.Cu")
		(at 172.6 137.3)
		(descr "Capacitor SMD 0402")
		(tags "capacitor SMD 0402")
		(property "Reference" "C7"
			(at 26.15 1.4 180)
			(layer "F.SilkS")
			(effects
				(font
					(size 0.7 0.7)
					(thickness 0.15)
				)
				(justify left bottom)
			)
		)
		(property "Value" "C_2u2_0402"
			(at 0 1.4 0)
			(layer "F.Fab")
			(effects
				(font
					(size 0.7 0.7)
					(thickness 0.15)
				)
				(justify left bottom)
			)
		)
		(property "Description" "SMD Multilayer Ceramic Capacitor, 2.2 µF, 10 V, 0402 [1005 Metric], ± 10%, X5R, C"
			(at 0 0 0)
			(layer "F.Fab")
			(hide yes)
			(effects
				(font
					(size 1.27 1.27)
					(thickness 0.15)
				)
			)
		)
		(property "Author" "Antmicro"
			(at 0 0 0)
			(layer "F.Fab")
			(hide yes)
			(effects
				(font
					(size 1 1)
					(thickness 0.15)
				)
			)
		)
		(property "Dielectric" ""
			(at 0 0 0)
			(layer "F.Fab")
			(hide yes)
			(effects
				(font
					(size 1 1)
					(thickness 0.15)
				)
			)
		)
		(property "License" "Apache-2.0"
			(at 0 0 0)
			(layer "F.Fab")
			(hide yes)
			(effects
				(font
					(size 1 1)
					(thickness 0.15)
				)
			)
		)
		(property "MPN" "C1005X5R1A225K050BC"
			(at 0 0 0)
			(layer "F.Fab")
			(hide yes)
			(effects
				(font
					(size 1 1)
					(thickness 0.15)
				)
			)
		)
		(property "Manufacturer" "TDK"
			(at 0 0 0)
			(layer "F.Fab")
			(hide yes)
			(effects
				(font
					(size 1 1)
					(thickness 0.15)
				)
			)
		)
		(property "Public" "False"
			(at 0 0 0)
			(layer "F.Fab")
			(hide yes)
			(effects
				(font
					(size 1 1)
					(thickness 0.15)
				)
			)
		)
		(property "Val" "2u2"
			(at 0 0 0)
			(layer "F.Fab")
			(hide yes)
			(effects
				(font
					(size 1 1)
					(thickness 0.15)
				)
			)
		)
		(property "Voltage" ""
			(at 0 0 0)
			(layer "F.Fab")
			(hide yes)
			(effects
				(font
					(size 1 1)
					(thickness 0.15)
				)
			)
		)
		(sheetfile "environment-sensor.kicad_sch")
		(attr smd)
		(fp_rect
			(start -0.925 -0.47)
			(end 0.925 0.47)
			(stroke
				(width 0.05)
				(type default)
			)
			(fill no)
			(layer "F.CrtYd")
		)
		(fp_line
			(start -0.494 -0.25)
			(end 0.504 -0.25)
			(stroke
				(width 0.15)
				(type solid)
			)
			(layer "F.Fab")
		)
		(fp_line
			(start -0.494 0.248)
			(end -0.494 -0.25)
			(stroke
				(width 0.15)
				(type solid)
			)
			(layer "F.Fab")
		)
		(fp_line
			(start 0.504 -0.25)
			(end 0.504 0.248)
			(stroke
				(width 0.15)
				(type solid)
			)
			(layer "F.Fab")
		)
		(fp_line
			(start 0.504 0.248)
			(end -0.494 0.248)
			(stroke
				(width 0.15)
				(type solid)
			)
			(layer "F.Fab")
		)
		(pad "1" smd roundrect
			(at -0.48 0)
			(size 0.59 0.64)
			(layers "F.Cu" "F.Mask" "F.Paste")
			(roundrect_rratio 0.25)
			(net 26 "+5V")
			(pintype "passive")
		)
		(pad "2" smd roundrect
			(at 0.48 0)
			(size 0.59 0.64)
			(layers "F.Cu" "F.Mask" "F.Paste")
			(roundrect_rratio 0.25)
			(net 1 "GND")
			(pintype "passive")
		)
	)
	(footprint "antmicro-footprints:SOT-723"
		(layer "F.Cu")
		(at 169.448 126.768)
		(property "Reference" "D5"
			(at 1.552 0.032 90)
			(layer "F.SilkS")
			(effects
				(font
					(size 0.65 0.65)
					(thickness 0.15)
				)
			)
		)
		(property "Value" "TPD2E009_SOT-9X3"
			(at -0.025 2.975 0)
			(layer "F.Fab")
			(effects
				(font
					(size 1 1)
					(thickness 0.15)
				)
			)
		)
		(property "Description" "TVS diode array, 8 kV, SOT-723, 5.5 V, 0.9 pF"
			(at 0 0 0)
			(layer "F.Fab")
			(hide yes)
			(effects
				(font
					(size 1.27 1.27)
					(thickness 0.15)
				)
			)
		)
		(property "Author" "Antmicro"
			(at 0 0 0)
			(layer "F.Fab")
			(hide yes)
			(effects
				(font
					(size 1 1)
					(thickness 0.15)
				)
			)
		)
		(property "License" "Apache-2.0"
			(at 0 0 0)
			(layer "F.Fab")
			(hide yes)
			(effects
				(font
					(size 1 1)
					(thickness 0.15)
				)
			)
		)
		(property "MPN" "TPD2E009DRTR"
			(at 0 0 0)
			(layer "F.Fab")
			(hide yes)
			(effects
				(font
					(size 1 1)
					(thickness 0.15)
				)
			)
		)
		(property "Manufacturer" "Texas Instruments"
			(at 0 0 0)
			(layer "F.Fab")
			(hide yes)
			(effects
				(font
					(size 1 1)
					(thickness 0.15)
				)
			)
		)
		(sheetfile "environment-sensor.kicad_sch")
		(attr smd)
		(fp_line
			(start -0.43 -0.1375)
			(end -0.43 0.1375)
			(stroke
				(width 0.15)
				(type solid)
			)
			(layer "F.SilkS")
		)
		(fp_line
			(start 0.43 -0.63)
			(end -0.2175 -0.63)
			(stroke
				(width 0.15)
				(type solid)
			)
			(layer "F.SilkS")
		)
		(fp_line
			(start 0.43 -0.23)
			(end 0.43 -0.63)
			(stroke
				(width 0.15)
				(type solid)
			)
			(layer "F.SilkS")
		)
		(fp_line
			(start 0.43 0.23)
			(end 0.43 0.63)
			(stroke
				(width 0.15)
				(type solid)
			)
			(layer "F.SilkS")
		)
		(fp_line
			(start 0.43 0.63)
			(end -0.22 0.63)
			(stroke
				(width 0.15)
				(type solid)
			)
			(layer "F.SilkS")
		)
		(fp_rect
			(start -0.83 -0.83)
			(end 0.83 0.83)
			(stroke
				(width 0.05)
				(type solid)
			)
			(fill no)
			(layer "F.CrtYd")
		)
		(fp_line
			(start -0.09 -0.53)
			(end -0.43 -0.19)
			(stroke
				(width 0.15)
				(type solid)
			)
			(layer "F.Fab")
		)
		(fp_line
			(start 0.424 -0.528)
			(end 0.424 0.524)
			(stroke
				(width 0.15)
				(type solid)
			)
			(layer "F.Fab")
		)
		(fp_line
			(start 0.424 0.524)
			(end -0.424 0.524)
			(stroke
				(width 0.15)
				(type solid)
			)
			(layer "F.Fab")
		)
		(fp_rect
			(start 0.424 0.524)
			(end -0.43 -0.528)
			(stroke
				(width 0.15)
				(type solid)
			)
			(fill no)
			(layer "F.Fab")
		)
		(fp_text user "${REFERENCE}"
			(at 0 0 0)
			(layer "F.Fab")
			(effects
				(font
					(size 0.2 0.2)
					(thickness 0.025)
				)
			)
		)
		(pad "1" smd rect
			(at -0.501 -0.401 270)
			(size 0.3 0.4)
			(layers "F.Cu" "F.Mask" "F.Paste")
			(net 6 "/USB_D_P")
			(pinfunction "1")
			(pintype "passive")
		)
		(pad "2" smd rect
			(at -0.501 0.399 270)
			(size 0.3 0.4)
			(layers "F.Cu" "F.Mask" "F.Paste")
			(net 7 "/USB_D_N")
			(pinfunction "2")
			(pintype "passive")
		)
		(pad "3" smd rect
			(at 0.499 -0.001 270)
			(size 0.3 0.4)
			(layers "F.Cu" "F.Mask" "F.Paste")
			(net 1 "GND")
			(pinfunction "3")
			(pintype "passive")
		)
	)
	(footprint "antmicro-footprints:R_0402_1005Metric"
		(layer "F.Cu")
		(at 180.75 126.25 90)
		(descr "Resistor SMD 0402")
		(tags "resistor SMD 0402")
		(property "Reference" "R20"
			(at 11.75 1.25 270)
			(layer "B.SilkS")
			(effects
				(font
					(size 0.7 0.7)
					(thickness 0.15)
				)
				(justify left bottom mirror)
			)
		)
		(property "Value" "R_0R_0402"
			(at 0 1.4 90)
			(layer "F.Fab")
			(effects
				(font
					(size 0.7 0.7)
					(thickness 0.15)
				)
				(justify left bottom)
			)
		)
		(property "Description" "SMD Chip Resistor, Jumper, 0 ohm, 100 mW, 0402 [1005 Metric], Thick Film, General Purpose"
			(at 0 0 90)
			(layer "F.Fab")
			(hide yes)
			(effects
				(font
					(size 1.27 1.27)
					(thickness 0.15)
				)
			)
		)
		(property "Author" "Antmicro"
			(at 307 -54.5 0)
			(layer "F.Fab")
			(hide yes)
			(effects
				(font
					(size 1 1)
					(thickness 0.15)
				)
			)
		)
		(property "Current" "1A"
			(at 307 -54.5 0)
			(layer "F.Fab")
			(hide yes)
			(effects
				(font
					(size 1 1)
					(thickness 0.15)
				)
			)
		)
		(property "License" "Apache-2.0"
			(at 307 -54.5 0)
			(layer "F.Fab")
			(hide yes)
			(effects
				(font
					(size 1 1)
					(thickness 0.15)
				)
			)
		)
		(property "MPN" "ERJ2GE0R00X"
			(at 307 -54.5 0)
			(layer "F.Fab")
			(hide yes)
			(effects
				(font
					(size 1 1)
					(thickness 0.15)
				)
			)
		)
		(property "Manufacturer" "Panasonic"
			(at 307 -54.5 0)
			(layer "F.Fab")
			(hide yes)
			(effects
				(font
					(size 1 1)
					(thickness 0.15)
				)
			)
		)
		(property "Public" "False"
			(at 307 -54.5 0)
			(layer "F.Fab")
			(hide yes)
			(effects
				(font
					(size 1 1)
					(thickness 0.15)
				)
			)
		)
		(property "Tolerance" ""
			(at 307 -54.5 0)
			(layer "F.Fab")
			(hide yes)
			(effects
				(font
					(size 1 1)
					(thickness 0.15)
				)
			)
		)
		(property "Val" "0R"
			(at 307 -54.5 0)
			(layer "F.Fab")
			(hide yes)
			(effects
				(font
					(size 1 1)
					(thickness 0.15)
				)
			)
		)
		(sheetfile "environment-sensor.kicad_sch")
		(attr smd)
		(fp_rect
			(start -0.925 -0.47)
			(end 0.925 0.47)
			(stroke
				(width 0.05)
				(type default)
			)
			(fill no)
			(layer "F.CrtYd")
		)
		(fp_rect
			(start -0.5 -0.25)
			(end 0.5 0.25)
			(stroke
				(width 0.15)
				(type solid)
			)
			(fill no)
			(layer "F.Fab")
		)
		(pad "1" smd roundrect
			(at -0.48 0 90)
			(size 0.59 0.64)
			(layers "F.Cu" "F.Mask" "F.Paste")
			(roundrect_rratio 0.25)
			(net 25 "JTDI")
			(pintype "passive")
		)
		(pad "2" smd roundrect
			(at 0.48 0 90)
			(size 0.59 0.64)
			(layers "F.Cu" "F.Mask" "F.Paste")
			(roundrect_rratio 0.25)
			(net 46 "Net-(U3-PA15)")
			(pintype "passive")
		)
	)
	(footprint "antmicro-footprints:R_0402_1005Metric"
		(layer "F.Cu")
		(at 175.55 137.3 180)
		(descr "Resistor SMD 0402")
		(tags "resistor SMD 0402")
		(property "Reference" "R17"
			(at -25.25 -1.4 180)
			(layer "F.SilkS")
			(effects
				(font
					(size 0.7 0.7)
					(thickness 0.15)
				)
				(justify left bottom)
			)
		)
		(property "Value" "R_470R_0402"
			(at 0 1.4 180)
			(layer "F.Fab")
			(effects
				(font
					(size 0.7 0.7)
					(thickness 0.15)
				)
				(justify left bottom)
			)
		)
		(property "Description" "SMD Chip Resistor, 470 ohm, ± 1%, 62.5 mW, 0402 [1005 Metric], Thick Film, General Purpose"
			(at 0 0 180)
			(layer "F.Fab")
			(hide yes)
			(effects
				(font
					(size 1.27 1.27)
					(thickness 0.15)
				)
			)
		)
		(property "Author" "Antmicro"
			(at 351.1 274.6 0)
			(layer "F.Fab")
			(hide yes)
			(effects
				(font
					(size 1 1)
					(thickness 0.15)
				)
			)
		)
		(property "License" "Apache-2.0"
			(at 351.1 274.6 0)
			(layer "F.Fab")
			(hide yes)
			(effects
				(font
					(size 1 1)
					(thickness 0.15)
				)
			)
		)
		(property "MPN" "CR0402-FX-4700GLF"
			(at 351.1 274.6 0)
			(layer "F.Fab")
			(hide yes)
			(effects
				(font
					(size 1 1)
					(thickness 0.15)
				)
			)
		)
		(property "Manufacturer" "Bourns"
			(at 351.1 274.6 0)
			(layer "F.Fab")
			(hide yes)
			(effects
				(font
					(size 1 1)
					(thickness 0.15)
				)
			)
		)
		(property "Public" "False"
			(at 351.1 274.6 0)
			(layer "F.Fab")
			(hide yes)
			(effects
				(font
					(size 1 1)
					(thickness 0.15)
				)
			)
		)
		(property "Tolerance" "1%"
			(at 351.1 274.6 0)
			(layer "F.Fab")
			(hide yes)
			(effects
				(font
					(size 1 1)
					(thickness 0.15)
				)
			)
		)
		(property "Val" "470R"
			(at 351.1 274.6 0)
			(layer "F.Fab")
			(hide yes)
			(effects
				(font
					(size 1 1)
					(thickness 0.15)
				)
			)
		)
		(sheetfile "environment-sensor.kicad_sch")
		(attr smd)
		(fp_rect
			(start -0.925 -0.47)
			(end 0.925 0.47)
			(stroke
				(width 0.05)
				(type default)
			)
			(fill no)
			(layer "F.CrtYd")
		)
		(fp_rect
			(start -0.5 -0.25)
			(end 0.5 0.25)
			(stroke
				(width 0.15)
				(type solid)
			)
			(fill no)
			(layer "F.Fab")
		)
		(pad "1" smd roundrect
			(at -0.48 0 180)
			(size 0.59 0.64)
			(layers "F.Cu" "F.Mask" "F.Paste")
			(roundrect_rratio 0.25)
			(net 1 "GND")
			(pintype "passive")
		)
		(pad "2" smd roundrect
			(at 0.48 0 180)
			(size 0.59 0.64)
			(layers "F.Cu" "F.Mask" "F.Paste")
			(roundrect_rratio 0.25)
			(net 11 "Net-(LD2-A)")
			(pintype "passive")
		)
	)
	(footprint "antmicro-footprints:R_0402_1005Metric"
		(layer "F.Cu")
		(at 176.246 123.678 90)
		(descr "Resistor SMD 0402")
		(tags "resistor SMD 0402")
		(property "Reference" "R2"
			(at -2.395 0.392 90)
			(layer "F.SilkS")
			(effects
				(font
					(size 0.7 0.7)
					(thickness 0.15)
				)
				(justify left bottom)
			)
		)
		(property "Value" "R_1k_0402"
			(at 0 1.4 90)
			(layer "F.Fab")
			(effects
				(font
					(size 0.7 0.7)
					(thickness 0.15)
				)
				(justify left bottom)
			)
		)
		(property "Description" "SMD Chip Resistor, 1 kohm, ± 1%, 63 mW, 0402 [1005 Metric], Thick Film, General Purpose"
			(at 0 0 90)
			(layer "F.Fab")
			(hide yes)
			(effects
				(font
					(size 1.27 1.27)
					(thickness 0.15)
				)
			)
		)
		(property "Author" "Antmicro"
			(at 299.924 -52.568 0)
			(layer "F.Fab")
			(hide yes)
			(effects
				(font
					(size 1 1)
					(thickness 0.15)
				)
			)
		)
		(property "License" "Apache-2.0"
			(at 299.924 -52.568 0)
			(layer "F.Fab")
			(hide yes)
			(effects
				(font
					(size 1 1)
					(thickness 0.15)
				)
			)
		)
		(property "MPN" "CR0402-FX-1001GLF"
			(at 299.924 -52.568 0)
			(layer "F.Fab")
			(hide yes)
			(effects
				(font
					(size 1 1)
					(thickness 0.15)
				)
			)
		)
		(property "Manufacturer" "Bourns"
			(at 299.924 -52.568 0)
			(layer "F.Fab")
			(hide yes)
			(effects
				(font
					(size 1 1)
					(thickness 0.15)
				)
			)
		)
		(property "Public" "False"
			(at 299.924 -52.568 0)
			(layer "F.Fab")
			(hide yes)
			(effects
				(font
					(size 1 1)
					(thickness 0.15)
				)
			)
		)
		(property "Tolerance" "1%"
			(at 299.924 -52.568 0)
			(layer "F.Fab")
			(hide yes)
			(effects
				(font
					(size 1 1)
					(thickness 0.15)
				)
			)
		)
		(property "Val" "1k"
			(at 299.924 -52.568 0)
			(layer "F.Fab")
			(hide yes)
			(effects
				(font
					(size 1 1)
					(thickness 0.15)
				)
			)
		)
		(sheetfile "environment-sensor.kicad_sch")
		(attr smd)
		(fp_rect
			(start -0.925 -0.47)
			(end 0.925 0.47)
			(stroke
				(width 0.05)
				(type default)
			)
			(fill no)
			(layer "F.CrtYd")
		)
		(fp_rect
			(start -0.5 -0.25)
			(end 0.5 0.25)
			(stroke
				(width 0.15)
				(type solid)
			)
			(fill no)
			(layer "F.Fab")
		)
		(pad "1" smd roundrect
			(at -0.48 0 90)
			(size 0.59 0.64)
			(layers "F.Cu" "F.Mask" "F.Paste")
			(roundrect_rratio 0.25)
			(net 26 "+5V")
			(pintype "passive")
		)
		(pad "2" smd roundrect
			(at 0.48 0 90)
			(size 0.59 0.64)
			(layers "F.Cu" "F.Mask" "F.Paste")
			(roundrect_rratio 0.25)
			(net 36 "Net-(U1-RESET#)")
			(pintype "passive")
		)
	)
)
